(kicad_pcb
	(version 20241229)
	(generator "pcbnew")
	(generator_version "9.0")
	(general
		(thickness 1.62)
		(legacy_teardrops no)
	)
	(paper "A3")
	(title_block
		(title "COM Express 7 Baseboard")
		(date "2025-02-04")
		(rev "1.1.2")
		(company "Antmicro Ltd")
		(comment 1 "www.antmicro.com")
		(comment 9 "footprints 82-87 of 802")
	)
	(layers
		(0 "F.Cu" signal)
		(4 "In1.Cu" signal)
		(6 "In2.Cu" signal)
		(8 "In3.Cu" signal)
		(10 "In4.Cu" signal)
		(12 "In5.Cu" signal)
		(14 "In6.Cu" signal)
		(2 "B.Cu" signal)
		(9 "F.Adhes" user "F.Adhesive")
		(11 "B.Adhes" user "B.Adhesive")
		(13 "F.Paste" user)
		(15 "B.Paste" user)
		(5 "F.SilkS" user "F.Silkscreen")
		(7 "B.SilkS" user "B.Silkscreen")
		(1 "F.Mask" user)
		(3 "B.Mask" user)
		(17 "Dwgs.User" user "User.Drawings")
		(19 "Cmts.User" user "User.Comments")
		(21 "Eco1.User" user "User.Eco1")
		(23 "Eco2.User" user "User.Eco2")
		(25 "Edge.Cuts" user)
		(27 "Margin" user)
		(31 "F.CrtYd" user "F.Courtyard")
		(29 "B.CrtYd" user "B.Courtyard")
		(35 "F.Fab" user)
		(33 "B.Fab" user)
	)
	(footprint "antmicro-footprints:R_0402_1005Metric"
		(layer "F.Cu")
		(at 213.98 135 -90)
		(descr "Resistor SMD 0402")
		(tags "resistor SMD 0402")
		(property "Reference" "R196"
			(at 0.81 -0.42 90)
			(layer "F.SilkS")
			(effects
				(font
					(size 0.7 0.7)
					(thickness 0.15)
				)
				(justify right bottom)
			)
		)
		(property "Value" "R_0R_0402"
			(at -1.011843 1.772047 90)
			(layer "F.Fab")
			(effects
				(font
					(size 0.7 0.7)
					(thickness 0.15)
				)
				(justify right bottom)
			)
		)
		(property "Datasheet" "https://industrial.panasonic.com/cdbs/www-data/pdf/RDA0000/AOA0000C301.pdf"
			(at 0 0 270)
			(layer "F.Fab")
			(hide yes)
			(effects
				(font
					(size 1.27 1.27)
					(thickness 0.15)
				)
			)
		)
		(property "Author" "Antmicro"
			(at 78.98 348.98 0)
			(layer "F.Fab")
			(hide yes)
			(effects
				(font
					(size 1 1)
					(thickness 0.15)
				)
			)
		)
		(property "Current" "1A"
			(at 78.98 348.98 0)
			(layer "F.Fab")
			(hide yes)
			(effects
				(font
					(size 1 1)
					(thickness 0.15)
				)
			)
		)
		(property "License" "Apache-2.0"
			(at 78.98 348.98 0)
			(layer "F.Fab")
			(hide yes)
			(effects
				(font
					(size 1 1)
					(thickness 0.15)
				)
			)
		)
		(property "MPN" "ERJ2GE0R00X"
			(at 78.98 348.98 0)
			(layer "F.Fab")
			(hide yes)
			(effects
				(font
					(size 1 1)
					(thickness 0.15)
				)
			)
		)
		(property "Manufacturer" "Panasonic"
			(at 78.98 348.98 0)
			(layer "F.Fab")
			(hide yes)
			(effects
				(font
					(size 1 1)
					(thickness 0.15)
				)
			)
		)
		(property "Public" "False"
			(at 78.98 348.98 0)
			(layer "F.Fab")
			(hide yes)
			(effects
				(font
					(size 1 1)
					(thickness 0.15)
				)
			)
		)
		(property "Tolerance" ""
			(at 78.98 348.98 0)
			(layer "F.Fab")
			(hide yes)
			(effects
				(font
					(size 1 1)
					(thickness 0.15)
				)
			)
		)
		(property "Val" "0R"
			(at 78.98 348.98 0)
			(layer "F.Fab")
			(hide yes)
			(effects
				(font
					(size 1 1)
					(thickness 0.15)
				)
			)
		)
		(sheetname "PCIe misc")
		(sheetfile "pcie_misc.kicad_sch")
		(attr smd)
		(fp_rect
			(start -0.925 -0.47)
			(end 0.925 0.47)
			(stroke
				(width 0.05)
				(type default)
			)
			(fill no)
			(layer "F.CrtYd")
		)
		(fp_rect
			(start -0.5 -0.25)
			(end 0.5 0.25)
			(stroke
				(width 0.15)
				(type solid)
			)
			(fill no)
			(layer "F.Fab")
		)
		(pad "1" smd roundrect
			(at -0.48 0 270)
			(size 0.59 0.64)
			(layers "F.Cu" "F.Mask" "F.Paste")
			(roundrect_rratio 0.25)
			(net 615 "/PCIe misc/DIF2+")
			(pintype "passive")
			(teardrops
				(best_length_ratio 0.2)
				(max_length 1)
				(best_width_ratio 0.9)
				(max_width 2)
				(curved_edges yes)
				(filter_ratio 0.9)
				(enabled yes)
				(allow_two_segments yes)
				(prefer_zone_connections yes)
			)
		)
		(pad "2" smd roundrect
			(at 0.48 0 270)
			(size 0.59 0.64)
			(layers "F.Cu" "F.Mask" "F.Paste")
			(roundrect_rratio 0.25)
			(net 21 "/M.2 key E/PCIE_{REF}.CK-")
			(pintype "passive")
			(teardrops
				(best_length_ratio 0.2)
				(max_length 1)
				(best_width_ratio 0.9)
				(max_width 2)
				(curved_edges yes)
				(filter_ratio 0.9)
				(enabled yes)
				(allow_two_segments yes)
				(prefer_zone_connections yes)
			)
		)
	)
	(footprint "antmicro-footprints:C_0402_1005Metric"
		(layer "F.Cu")
		(at 258.730708 78.085 -90)
		(descr "Capacitor SMD 0402")
		(tags "capacitor SMD 0402")
		(property "Reference" "C86"
			(at 0.8 -0.465 90)
			(layer "F.SilkS")
			(effects
				(font
					(size 0.7 0.7)
					(thickness 0.15)
				)
				(justify right bottom)
			)
		)
		(property "Value" "C_100n_0402"
			(at -1.022927 2.155213 90)
			(layer "F.Fab")
			(effects
				(font
					(size 0.7 0.7)
					(thickness 0.15)
				)
				(justify right bottom)
			)
		)
		(property "Datasheet" "https://www.murata.com/products/productdetail?partno=GRM155R61H104KE14%23"
			(at 0 0 270)
			(layer "F.Fab")
			(hide yes)
			(effects
				(font
					(size 1.27 1.27)
					(thickness 0.15)
				)
			)
		)
		(property "Author" "Antmicro"
			(at 180.645708 336.815708 0)
			(layer "F.Fab")
			(hide yes)
			(effects
				(font
					(size 1 1)
					(thickness 0.15)
				)
			)
		)
		(property "Dielectric" "X5R"
			(at 180.645708 336.815708 0)
			(layer "F.Fab")
			(hide yes)
			(effects
				(font
					(size 1 1)
					(thickness 0.15)
				)
			)
		)
		(property "License" "Apache-2.0"
			(at 180.645708 336.815708 0)
			(layer "F.Fab")
			(hide yes)
			(effects
				(font
					(size 1 1)
					(thickness 0.15)
				)
			)
		)
		(property "MPN" "GRM155R61H104KE14D"
			(at 180.645708 336.815708 0)
			(layer "F.Fab")
			(hide yes)
			(effects
				(font
					(size 1 1)
					(thickness 0.15)
				)
			)
		)
		(property "Manufacturer" "Murata"
			(at 180.645708 336.815708 0)
			(layer "F.Fab")
			(hide yes)
			(effects
				(font
					(size 1 1)
					(thickness 0.15)
				)
			)
		)
		(property "Public" "False"
			(at 180.645708 336.815708 0)
			(layer "F.Fab")
			(hide yes)
			(effects
				(font
					(size 1 1)
					(thickness 0.15)
				)
			)
		)
		(property "Val" "100n"
			(at 180.645708 336.815708 0)
			(layer "F.Fab")
			(hide yes)
			(effects
				(font
					(size 1 1)
					(thickness 0.15)
				)
			)
		)
		(property "Voltage" "50V"
			(at 180.645708 336.815708 0)
			(layer "F.Fab")
			(hide yes)
			(effects
				(font
					(size 1 1)
					(thickness 0.15)
				)
			)
		)
		(sheetname "Misc")
		(sheetfile "misc.kicad_sch")
		(attr smd)
		(fp_rect
			(start -0.925 -0.47)
			(end 0.925 0.47)
			(stroke
				(width 0.05)
				(type default)
			)
			(fill no)
			(layer "F.CrtYd")
		)
		(fp_line
			(start -0.494 0.248)
			(end -0.494 -0.25)
			(stroke
				(width 0.15)
				(type solid)
			)
			(layer "F.Fab")
		)
		(fp_line
			(start 0.504 0.248)
			(end -0.494 0.248)
			(stroke
				(width 0.15)
				(type solid)
			)
			(layer "F.Fab")
		)
		(fp_line
			(start -0.494 -0.25)
			(end 0.504 -0.25)
			(stroke
				(width 0.15)
				(type solid)
			)
			(layer "F.Fab")
		)
		(fp_line
			(start 0.504 -0.25)
			(end 0.504 0.248)
			(stroke
				(width 0.15)
				(type solid)
			)
			(layer "F.Fab")
		)
		(pad "1" smd roundrect
			(at -0.48 0 270)
			(size 0.59 0.64)
			(layers "F.Cu" "F.Mask" "F.Paste")
			(roundrect_rratio 0.25)
			(net 1 "GND")
			(pintype "passive")
			(teardrops
				(best_length_ratio 0.2)
				(max_length 1)
				(best_width_ratio 0.9)
				(max_width 2)
				(curved_edges yes)
				(filter_ratio 0.9)
				(enabled yes)
				(allow_two_segments yes)
				(prefer_zone_connections yes)
			)
		)
		(pad "2" smd roundrect
			(at 0.48 0 270)
			(size 0.59 0.64)
			(layers "F.Cu" "F.Mask" "F.Paste")
			(roundrect_rratio 0.25)
			(net 2 "+3V3")
			(pintype "passive")
			(teardrops
				(best_length_ratio 0.2)
				(max_length 1)
				(best_width_ratio 0.9)
				(max_width 2)
				(curved_edges yes)
				(filter_ratio 0.9)
				(enabled yes)
				(allow_two_segments yes)
				(prefer_zone_connections yes)
			)
		)
	)
	(footprint "antmicro-footprints:TP_SMD_0.75mm"
		(layer "F.Cu")
		(at 155.7 128.71)
		(property "Reference" "TP72"
			(at 0.4 -3.3 90)
			(layer "F.SilkS")
			(effects
				(font
					(size 0.7 0.7)
					(thickness 0.15)
				)
				(justify left bottom)
			)
		)
		(property "Value" "TP_0.75mm_SMD"
			(at 0 1.2 0)
			(layer "F.Fab")
			(effects
				(font
					(size 0.7 0.7)
					(thickness 0.15)
				)
				(justify left bottom)
			)
		)
		(property "Author" "Antmicro"
			(at 0 0 0)
			(layer "F.Fab")
			(hide yes)
			(effects
				(font
					(size 1 1)
					(thickness 0.15)
				)
			)
		)
		(property "License" "Apache-2.0"
			(at 0 0 0)
			(layer "F.Fab")
			(hide yes)
			(effects
				(font
					(size 1 1)
					(thickness 0.15)
				)
			)
		)
		(property "MPN" ""
			(at 0 0 0)
			(layer "F.Fab")
			(hide yes)
			(effects
				(font
					(size 1 1)
					(thickness 0.15)
				)
			)
		)
		(property "Manufacturer" ""
			(at 0 0 0)
			(layer "F.Fab")
			(hide yes)
			(effects
				(font
					(size 1 1)
					(thickness 0.15)
				)
			)
		)
		(property "Public" "False"
			(at 0 0 0)
			(layer "F.Fab")
			(hide yes)
			(effects
				(font
					(size 1 1)
					(thickness 0.15)
				)
			)
		)
		(sheetname "KR to SFI #1")
		(sheetfile "kr_sfi.kicad_sch")
		(attr exclude_from_pos_files exclude_from_bom)
		(fp_circle
			(center 0 0)
			(end 0.475 0)
			(stroke
				(width 0.05)
				(type default)
			)
			(fill no)
			(layer "F.CrtYd")
		)
		(pad "1" smd circle
			(at 0 0)
			(size 0.75 0.75)
			(layers "F.Cu" "F.Mask")
			(net 735 "Net-(U43A-LS_OK_{IN_A})")
			(pinfunction "1")
			(pintype "passive")
			(teardrops
				(best_length_ratio 0.4)
				(max_length 1)
				(best_width_ratio 0.9)
				(max_width 2)
				(curved_edges yes)
				(filter_ratio 0.9)
				(enabled yes)
				(allow_two_segments yes)
				(prefer_zone_connections yes)
			)
		)
	)
	(footprint "antmicro-footprints:R_0402_1005Metric"
		(layer "F.Cu")
		(at 142.37 144.05)
		(descr "Resistor SMD 0402")
		(tags "resistor SMD 0402")
		(property "Reference" "R247"
			(at -3.72 1.16 0)
			(layer "F.SilkS")
			(effects
				(font
					(size 0.7 0.7)
					(thickness 0.15)
				)
				(justify left bottom)
			)
		)
		(property "Value" "R_0R_0402"
			(at -1.011843 1.772047 0)
			(layer "F.Fab")
			(effects
				(font
					(size 0.7 0.7)
					(thickness 0.15)
				)
				(justify left bottom)
			)
		)
		(property "Datasheet" "https://industrial.panasonic.com/cdbs/www-data/pdf/RDA0000/AOA0000C301.pdf"
			(at 0 0 0)
			(layer "F.Fab")
			(hide yes)
			(effects
				(font
					(size 1.27 1.27)
					(thickness 0.15)
				)
			)
		)
		(property "Author" "Antmicro"
			(at 0 0 0)
			(layer "F.Fab")
			(hide yes)
			(effects
				(font
					(size 1 1)
					(thickness 0.15)
				)
			)
		)
		(property "Current" "1A"
			(at 0 0 0)
			(layer "F.Fab")
			(hide yes)
			(effects
				(font
					(size 1 1)
					(thickness 0.15)
				)
			)
		)
		(property "License" "Apache-2.0"
			(at 0 0 0)
			(layer "F.Fab")
			(hide yes)
			(effects
				(font
					(size 1 1)
					(thickness 0.15)
				)
			)
		)
		(property "MPN" "ERJ2GE0R00X"
			(at 0 0 0)
			(layer "F.Fab")
			(hide yes)
			(effects
				(font
					(size 1 1)
					(thickness 0.15)
				)
			)
		)
		(property "Manufacturer" "Panasonic"
			(at 0 0 0)
			(layer "F.Fab")
			(hide yes)
			(effects
				(font
					(size 1 1)
					(thickness 0.15)
				)
			)
		)
		(property "Public" "False"
			(at 0 0 0)
			(layer "F.Fab")
			(hide yes)
			(effects
				(font
					(size 1 1)
					(thickness 0.15)
				)
			)
		)
		(property "Tolerance" ""
			(at 0 0 0)
			(layer "F.Fab")
			(hide yes)
			(effects
				(font
					(size 1 1)
					(thickness 0.15)
				)
			)
		)
		(property "Val" "0R"
			(at 0 0 0)
			(layer "F.Fab")
			(hide yes)
			(effects
				(font
					(size 1 1)
					(thickness 0.15)
				)
			)
		)
		(sheetname "KR to SFI #1")
		(sheetfile "kr_sfi.kicad_sch")
		(attr smd)
		(fp_rect
			(start -0.925 -0.47)
			(end 0.925 0.47)
			(stroke
				(width 0.05)
				(type default)
			)
			(fill no)
			(layer "F.CrtYd")
		)
		(fp_rect
			(start -0.5 -0.25)
			(end 0.5 0.25)
			(stroke
				(width 0.15)
				(type solid)
			)
			(fill no)
			(layer "F.Fab")
		)
		(pad "1" smd roundrect
			(at -0.48 0)
			(size 0.59 0.64)
			(layers "F.Cu" "F.Mask" "F.Paste")
			(roundrect_rratio 0.25)
			(net 648 "/2xSFP+/KR to SFI #1/MDIO_R")
			(pintype "passive")
			(teardrops
				(best_length_ratio 0.2)
				(max_length 1)
				(best_width_ratio 0.9)
				(max_width 2)
				(curved_edges yes)
				(filter_ratio 0.9)
				(enabled yes)
				(allow_two_segments yes)
				(prefer_zone_connections yes)
			)
		)
		(pad "2" smd roundrect
			(at 0.48 0)
			(size 0.59 0.64)
			(layers "F.Cu" "F.Mask" "F.Paste")
			(roundrect_rratio 0.25)
			(net 649 "/2xSFP+/KR to SFI #1/MDIO")
			(pintype "passive")
			(teardrops
				(best_length_ratio 0.2)
				(max_length 1)
				(best_width_ratio 0.9)
				(max_width 2)
				(curved_edges yes)
				(filter_ratio 0.9)
				(enabled yes)
				(allow_two_segments yes)
				(prefer_zone_connections yes)
			)
		)
	)
	(footprint "antmicro-footprints:R_0402_1005Metric"
		(layer "F.Cu")
		(at 243.8 132.354 90)
		(descr "Resistor SMD 0402")
		(tags "resistor SMD 0402")
		(property "Reference" "R323"
			(at -3.706 0.45 90)
			(layer "F.SilkS")
			(effects
				(font
					(size 0.7 0.7)
					(thickness 0.15)
				)
				(justify left bottom)
			)
		)
		(property "Value" "R_1k_0402"
			(at -1.011843 1.772047 90)
			(layer "F.Fab")
			(effects
				(font
					(size 0.7 0.7)
					(thickness 0.15)
				)
				(justify left bottom)
			)
		)
		(property "Datasheet" "https://www.bourns.com/docs/product-datasheets/cr.pdf"
			(at 0 0 90)
			(layer "F.Fab")
			(hide yes)
			(effects
				(font
					(size 1.27 1.27)
					(thickness 0.15)
				)
			)
		)
		(property "Author" "Antmicro"
			(at 376.154 -111.446 0)
			(layer "F.Fab")
			(hide yes)
			(effects
				(font
					(size 1 1)
					(thickness 0.15)
				)
			)
		)
		(property "License" "Apache-2.0"
			(at 376.154 -111.446 0)
			(layer "F.Fab")
			(hide yes)
			(effects
				(font
					(size 1 1)
					(thickness 0.15)
				)
			)
		)
		(property "MPN" "CR0402-FX-1001GLF"
			(at 376.154 -111.446 0)
			(layer "F.Fab")
			(hide yes)
			(effects
				(font
					(size 1 1)
					(thickness 0.15)
				)
			)
		)
		(property "Manufacturer" "Bourns"
			(at 376.154 -111.446 0)
			(layer "F.Fab")
			(hide yes)
			(effects
				(font
					(size 1 1)
					(thickness 0.15)
				)
			)
		)
		(property "Public" "False"
			(at 376.154 -111.446 0)
			(layer "F.Fab")
			(hide yes)
			(effects
				(font
					(size 1 1)
					(thickness 0.15)
				)
			)
		)
		(property "Tolerance" "1%"
			(at 376.154 -111.446 0)
			(layer "F.Fab")
			(hide yes)
			(effects
				(font
					(size 1 1)
					(thickness 0.15)
				)
			)
		)
		(property "Val" "1k"
			(at 376.154 -111.446 0)
			(layer "F.Fab")
			(hide yes)
			(effects
				(font
					(size 1 1)
					(thickness 0.15)
				)
			)
		)
		(sheetname "Com Express 7 MGMT")
		(sheetfile "com_express_7_mgmt.kicad_sch")
		(attr smd)
		(fp_rect
			(start -0.925 -0.47)
			(end 0.925 0.47)
			(stroke
				(width 0.05)
				(type default)
			)
			(fill no)
			(layer "F.CrtYd")
		)
		(fp_rect
			(start -0.5 -0.25)
			(end 0.5 0.25)
			(stroke
				(width 0.15)
				(type solid)
			)
			(fill no)
			(layer "F.Fab")
		)
		(pad "1" smd roundrect
			(at -0.48 0 90)
			(size 0.59 0.64)
			(layers "F.Cu" "F.Mask" "F.Paste")
			(roundrect_rratio 0.25)
			(net 533 "/Com Express 7 MGMT/PSON")
			(pintype "passive")
			(teardrops
				(best_length_ratio 0.2)
				(max_length 1)
				(best_width_ratio 0.9)
				(max_width 2)
				(curved_edges yes)
				(filter_ratio 0.9)
				(enabled yes)
				(allow_two_segments yes)
				(prefer_zone_connections yes)
			)
		)
		(pad "2" smd roundrect
			(at 0.48 0 90)
			(size 0.59 0.64)
			(layers "F.Cu" "F.Mask" "F.Paste")
			(roundrect_rratio 0.25)
			(net 873 "Net-(U34-EN)")
			(pintype "passive")
			(teardrops
				(best_length_ratio 0.2)
				(max_length 1)
				(best_width_ratio 0.9)
				(max_width 2)
				(curved_edges yes)
				(filter_ratio 0.9)
				(enabled yes)
				(allow_two_segments yes)
				(prefer_zone_connections yes)
			)
		)
	)
	(footprint "antmicro-footprints:TP_SMD_0.75mm"
		(layer "F.Cu")
		(at 127.79 129.56)
		(property "Reference" "TP95"
			(at 0.46 -1.25 90)
			(layer "F.SilkS")
			(effects
				(font
					(size 0.7 0.7)
					(thickness 0.15)
				)
				(justify left bottom)
			)
		)
		(property "Value" "TP_0.75mm_SMD"
			(at 0 1.2 0)
			(layer "F.Fab")
			(effects
				(font
					(size 0.7 0.7)
					(thickness 0.15)
				)
				(justify left bottom)
			)
		)
		(property "Author" "Antmicro"
			(at 0 0 0)
			(layer "F.Fab")
			(hide yes)
			(effects
				(font
					(size 1 1)
					(thickness 0.15)
				)
			)
		)
		(property "License" "Apache-2.0"
			(at 0 0 0)
			(layer "F.Fab")
			(hide yes)
			(effects
				(font
					(size 1 1)
					(thickness 0.15)
				)
			)
		)
		(property "MPN" ""
			(at 0 0 0)
			(layer "F.Fab")
			(hide yes)
			(effects
				(font
					(size 1 1)
					(thickness 0.15)
				)
			)
		)
		(property "Manufacturer" ""
			(at 0 0 0)
			(layer "F.Fab")
			(hide yes)
			(effects
				(font
					(size 1 1)
					(thickness 0.15)
				)
			)
		)
		(property "Public" "False"
			(at 0 0 0)
			(layer "F.Fab")
			(hide yes)
			(effects
				(font
					(size 1 1)
					(thickness 0.15)
				)
			)
		)
		(sheetname "KR to SFI #2")
		(sheetfile "kr_sfi.kicad_sch")
		(attr exclude_from_pos_files exclude_from_bom)
		(fp_circle
			(center 0 0)
			(end 0.475 0)
			(stroke
				(width 0.05)
				(type default)
			)
			(fill no)
			(layer "F.CrtYd")
		)
		(pad "1" smd circle
			(at 0 0)
			(size 0.75 0.75)
			(layers "F.Cu" "F.Mask")
			(net 758 "Net-(U45B-LS_OK_{IN_B})")
			(pinfunction "1")
			(pintype "passive")
			(teardrops
				(best_length_ratio 0.4)
				(max_length 1)
				(best_width_ratio 0.9)
				(max_width 2)
				(curved_edges yes)
				(filter_ratio 0.9)
				(enabled yes)
				(allow_two_segments yes)
				(prefer_zone_connections yes)
			)
		)
	)
)
